FILE_TYPE = MULTI_PHYS_TABLE;

PART 'MP5016GQHLZ'

{========================================================================================}
:VALUE           | PART_TYPE | MATERIAL | PART_NUMBER    = STANDARD    | LIFECYCLE     | PART_NUMBER   | JEDEC_TYPE   | DESCRIPTION                   | MANUFTR | MANUF_PN        | RD_CMPLS_LVL | CMPLS_LVL | FROM_PJ    | CLASS | DIP_SMD | DATA                    | EE_CHECK_LIST | FP_ECN | PSL | CREATOR | STATUS | MSD | ESD_CDM | ESD_HBM | ESD_MM | PIN_LENGTH_SHORT_PIN | PIN_LENGTH_LONG_PIN | CREATEDAY  ;
{========================================================================================}
 'MP5016GQH-L-Z' | 'SMLF'    | 'IC'     | 'AL005016007'(!) = ''               | ''               | 'AL005016007' |'QFN8_2X1-5'| 'IC (10P) MP5016GQH-L-Z(QFN)' | 'MPS'   | 'MP5016GQH-L-Z' | 'EP(V1)'     | 'EP(V1)'  | 'F0CE-SAM' | 'IC'  | ''      | 'MPS_MP5016GQH-L-Z.pdf' | ''            | ''     | ''  | ''      | ''     | ''  | ''      | ''      | ''     | '0 MILS'             | '0 MILS'            | '20210519'
 'MP5016GQH-L-Z' | 'SMLF'    | 'EMPTY'  | 'AL005016007'(!) = ''               | ''               | 'AL005016007' |'QFN8_2X1-5'| 'IC (10P) MP5016GQH-L-Z(QFN)' | 'MPS'   | 'MP5016GQH-L-Z' | 'EP(V1)'     | 'EP(V1)'  | 'F0CE-SAM' | 'IC'  | ''      | 'MPS_MP5016GQH-L-Z.pdf' | ''            | ''     | ''  | ''      | ''     | ''  | ''      | ''      | ''     | '0 MILS'             | '0 MILS'            | '20210519'

END_PART

END.

